(kicad_pcb
	(version 20260206)
	(generator "pcbnew")
	(generator_version "10.0")
	(general
		(thickness 1.6)
		(legacy_teardrops no)
	)
	(paper "A4")
	(title_block
		(title "03242023_DA0F0TMBIJ0_F0T_Motherboard_J_brd_V01_OCP.brd")
		(comment 1 "Grand Teton / footprints 2287-2292 of 6105")
	)
	(layers
		(0 "F.Cu" signal "TOP")
		(4 "In1.Cu" signal "GND")
		(6 "In2.Cu" signal "IN1")
		(8 "In3.Cu" signal "GND1")
		(10 "In4.Cu" signal "IN2")
		(12 "In5.Cu" signal "GND2")
		(14 "In6.Cu" signal "IN3")
		(16 "In7.Cu" signal "GND3")
		(18 "In8.Cu" signal "VCC")
		(20 "In9.Cu" signal "VCC1")
		(22 "In10.Cu" signal "GND4")
		(24 "In11.Cu" signal "IN4")
		(26 "In12.Cu" signal "GND5")
		(28 "In13.Cu" signal "IN5")
		(30 "In14.Cu" signal "GND6")
		(32 "In15.Cu" signal "IN6")
		(34 "In16.Cu" signal "GND7")
		(2 "B.Cu" signal "BOTTOM")
		(9 "F.Adhes" user "F.Adhesive")
		(11 "B.Adhes" user "B.Adhesive")
		(13 "F.Paste" user "Package Geometry/Pastemask Top")
		(15 "B.Paste" user "Package Geometry/Pastemask Bottom")
		(5 "F.SilkS" user "Ref Des/Silkscreen Top")
		(7 "B.SilkS" user "Ref Des/Silkscreen Bottom")
		(1 "F.Mask" user "Board Geometry/Soldermask Top")
		(3 "B.Mask" user "Board Geometry/Soldermask Bottom")
		(17 "Dwgs.User" user "User.Drawings")
		(19 "Cmts.User" user "User.Comments")
		(21 "Eco1.User" user "User.Eco1")
		(23 "Eco2.User" user "User.Eco2")
		(25 "Edge.Cuts" user "Board Geometry/Outline")
		(27 "Margin" user)
		(31 "F.CrtYd" user "Package Geometry/Place Bound Top")
		(29 "B.CrtYd" user "Package Geometry/Place Bound Bottom")
		(35 "F.Fab" user "Ref Des/Assembly Top")
		(33 "B.Fab" user "Ref Des/Assembly Bottom")
	)
	(footprint ""
		(layer "F.Cu")
		(at 144.88541 -126.630684)
		(property "Reference" "C1817"
			(at 0 0 0)
			(layer "F.SilkS")
			(hide yes)
			(effects
				(font
					(size 1.27 1.27)
				)
			)
		)
		(property "Value" ""
			(at 0 0 0)
			(layer "F.Fab")
			(effects
				(font
					(size 1.27 1.27)
				)
			)
		)
		(duplicate_pad_numbers_are_jumpers no)
		(fp_line
			(start -0.7874 -0.4064)
			(end 0.7874 -0.4064)
			(stroke
				(width 0.1524)
				(type default)
			)
			(layer "F.SilkS")
		)
		(fp_line
			(start -0.7874 0.4064)
			(end -0.7874 -0.4064)
			(stroke
				(width 0.1524)
				(type default)
			)
			(layer "F.SilkS")
		)
		(fp_line
			(start 0.7874 -0.4064)
			(end 0.7874 0.4064)
			(stroke
				(width 0.1524)
				(type default)
			)
			(layer "F.SilkS")
		)
		(fp_line
			(start 0.7874 0.4064)
			(end -0.7874 0.4064)
			(stroke
				(width 0.1524)
				(type default)
			)
			(layer "F.SilkS")
		)
		(fp_line
			(start -0.67945 -0.305054)
			(end -0.12065 -0.305054)
			(stroke
				(width 0.1)
				(type default)
			)
			(layer "F.Fab")
		)
		(fp_line
			(start -0.67945 0.3048)
			(end -0.67945 -0.305054)
			(stroke
				(width 0.1)
				(type default)
			)
			(layer "F.Fab")
		)
		(fp_line
			(start -0.12065 -0.305054)
			(end -0.12065 -0.2794)
			(stroke
				(width 0.1)
				(type default)
			)
			(layer "F.Fab")
		)
		(fp_line
			(start -0.12065 -0.2794)
			(end 0.12065 -0.2794)
			(stroke
				(width 0.1)
				(type default)
			)
			(layer "F.Fab")
		)
		(fp_line
			(start -0.12065 0.2794)
			(end -0.12065 0.3048)
			(stroke
				(width 0.1)
				(type default)
			)
			(layer "F.Fab")
		)
		(fp_line
			(start -0.12065 0.3048)
			(end -0.67945 0.3048)
			(stroke
				(width 0.1)
				(type default)
			)
			(layer "F.Fab")
		)
		(fp_line
			(start 0.120396 0.2794)
			(end -0.12065 0.2794)
			(stroke
				(width 0.1)
				(type default)
			)
			(layer "F.Fab")
		)
		(fp_line
			(start 0.120396 0.3048)
			(end 0.120396 0.2794)
			(stroke
				(width 0.1)
				(type default)
			)
			(layer "F.Fab")
		)
		(fp_line
			(start 0.12065 -0.3048)
			(end 0.67945 -0.3048)
			(stroke
				(width 0.1)
				(type default)
			)
			(layer "F.Fab")
		)
		(fp_line
			(start 0.12065 -0.2794)
			(end 0.12065 -0.3048)
			(stroke
				(width 0.1)
				(type default)
			)
			(layer "F.Fab")
		)
		(fp_line
			(start 0.67945 -0.3048)
			(end 0.67945 0.3048)
			(stroke
				(width 0.1)
				(type default)
			)
			(layer "F.Fab")
		)
		(fp_line
			(start 0.67945 0.3048)
			(end 0.120396 0.3048)
			(stroke
				(width 0.1)
				(type default)
			)
			(layer "F.Fab")
		)
		(pad "1" smd circle
			(at -0.40005 0)
			(size 0 0)
			(layers "F.Cu" "F.Mask" "F.Paste")
			(net "P3V3_AUX")
		)
		(pad "2" smd circle
			(at 0.40005 0)
			(size 0 0)
			(layers "F.Cu" "F.Mask" "F.Paste")
			(net "GND")
		)
	)
	(footprint ""
		(layer "F.Cu")
		(at 129.7559 -24.775668 180)
		(property "Reference" "C2284"
			(at 0 0 180)
			(layer "F.SilkS")
			(hide yes)
			(effects
				(font
					(size 1.27 1.27)
				)
			)
		)
		(property "Value" ""
			(at 0 0 180)
			(layer "F.Fab")
			(effects
				(font
					(size 1.27 1.27)
				)
			)
		)
		(duplicate_pad_numbers_are_jumpers no)
		(fp_line
			(start 1.524 0.762)
			(end -1.524 0.762)
			(stroke
				(width 0.1524)
				(type default)
			)
			(layer "F.SilkS")
		)
		(fp_line
			(start 1.524 -0.762)
			(end 1.524 0.762)
			(stroke
				(width 0.1524)
				(type default)
			)
			(layer "F.SilkS")
		)
		(fp_line
			(start -1.524 0.762)
			(end -1.524 -0.762)
			(stroke
				(width 0.1524)
				(type default)
			)
			(layer "F.SilkS")
		)
		(fp_line
			(start -1.524 -0.762)
			(end 1.524 -0.762)
			(stroke
				(width 0.1524)
				(type default)
			)
			(layer "F.SilkS")
		)
		(fp_line
			(start 1.1049 0.724916)
			(end 1.1049 -0.724916)
			(stroke
				(width 0.1)
				(type default)
			)
			(layer "F.Fab")
		)
		(fp_line
			(start 1.1049 -0.724916)
			(end -1.1049 -0.724916)
			(stroke
				(width 0.1)
				(type default)
			)
			(layer "F.Fab")
		)
		(fp_line
			(start -1.1049 0.724916)
			(end 1.1049 0.724916)
			(stroke
				(width 0.1)
				(type default)
			)
			(layer "F.Fab")
		)
		(fp_line
			(start -1.1049 -0.724916)
			(end -1.1049 0.724916)
			(stroke
				(width 0.1)
				(type default)
			)
			(layer "F.Fab")
		)
		(pad "1" smd rect
			(at -0.889 0)
			(size 1.016 1.27)
			(layers "F.Cu" "F.Mask" "F.Paste")
			(net "P3V3_AUX_USB_BUF")
		)
		(pad "2" smd rect
			(at 0.889 0)
			(size 1.016 1.27)
			(layers "F.Cu" "F.Mask" "F.Paste")
			(net "GND")
		)
	)
	(footprint ""
		(layer "F.Cu")
		(at 307.77688 -53.050948 90)
		(property "Reference" "R145"
			(at 0 0 90)
			(layer "F.SilkS")
			(hide yes)
			(effects
				(font
					(size 1.27 1.27)
				)
			)
		)
		(property "Value" ""
			(at 0 0 90)
			(layer "F.Fab")
			(effects
				(font
					(size 1.27 1.27)
				)
			)
		)
		(duplicate_pad_numbers_are_jumpers no)
		(fp_line
			(start 0.7874 -0.4064)
			(end 0.7874 0.4064)
			(stroke
				(width 0.1524)
				(type default)
			)
			(layer "F.SilkS")
		)
		(fp_line
			(start -0.7874 -0.4064)
			(end 0.7874 -0.4064)
			(stroke
				(width 0.1524)
				(type default)
			)
			(layer "F.SilkS")
		)
		(fp_line
			(start 0.7874 0.4064)
			(end -0.7874 0.4064)
			(stroke
				(width 0.1524)
				(type default)
			)
			(layer "F.SilkS")
		)
		(fp_line
			(start -0.7874 0.4064)
			(end -0.7874 -0.4064)
			(stroke
				(width 0.1524)
				(type default)
			)
			(layer "F.SilkS")
		)
		(fp_line
			(start -0.12065 -0.305054)
			(end -0.12065 -0.2794)
			(stroke
				(width 0.1)
				(type default)
			)
			(layer "F.Fab")
		)
		(fp_line
			(start -0.67945 -0.305054)
			(end -0.12065 -0.305054)
			(stroke
				(width 0.1)
				(type default)
			)
			(layer "F.Fab")
		)
		(fp_line
			(start 0.67945 -0.3048)
			(end 0.67945 0.3048)
			(stroke
				(width 0.1)
				(type default)
			)
			(layer "F.Fab")
		)
		(fp_line
			(start 0.12065 -0.3048)
			(end 0.67945 -0.3048)
			(stroke
				(width 0.1)
				(type default)
			)
			(layer "F.Fab")
		)
		(fp_line
			(start 0.12065 -0.2794)
			(end 0.12065 -0.3048)
			(stroke
				(width 0.1)
				(type default)
			)
			(layer "F.Fab")
		)
		(fp_line
			(start -0.12065 -0.2794)
			(end 0.12065 -0.2794)
			(stroke
				(width 0.1)
				(type default)
			)
			(layer "F.Fab")
		)
		(fp_line
			(start 0.120396 0.2794)
			(end -0.12065 0.2794)
			(stroke
				(width 0.1)
				(type default)
			)
			(layer "F.Fab")
		)
		(fp_line
			(start -0.12065 0.2794)
			(end -0.12065 0.3048)
			(stroke
				(width 0.1)
				(type default)
			)
			(layer "F.Fab")
		)
		(fp_line
			(start 0.67945 0.3048)
			(end 0.120396 0.3048)
			(stroke
				(width 0.1)
				(type default)
			)
			(layer "F.Fab")
		)
		(fp_line
			(start 0.120396 0.3048)
			(end 0.120396 0.2794)
			(stroke
				(width 0.1)
				(type default)
			)
			(layer "F.Fab")
		)
		(fp_line
			(start -0.12065 0.3048)
			(end -0.67945 0.3048)
			(stroke
				(width 0.1)
				(type default)
			)
			(layer "F.Fab")
		)
		(fp_line
			(start -0.67945 0.3048)
			(end -0.67945 -0.305054)
			(stroke
				(width 0.1)
				(type default)
			)
			(layer "F.Fab")
		)
		(pad "1" smd circle
			(at -0.40005 0 90)
			(size 0 0)
			(layers "F.Cu" "F.Mask" "F.Paste")
			(net "PVNN_TERM_CPU0")
		)
		(pad "2" smd circle
			(at 0.40005 0 90)
			(size 0 0)
			(layers "F.Cu" "F.Mask" "F.Paste")
			(net "PECI_PCH_R")
		)
	)
	(footprint ""
		(layer "F.Cu")
		(at 324.919594 -32.371538 135)
		(property "Reference" "R120"
			(at 0 0 135)
			(layer "F.SilkS")
			(hide yes)
			(effects
				(font
					(size 1.27 1.27)
				)
			)
		)
		(property "Value" ""
			(at 0 0 135)
			(layer "F.Fab")
			(effects
				(font
					(size 1.27 1.27)
				)
			)
		)
		(duplicate_pad_numbers_are_jumpers no)
		(fp_line
			(start 1.295492 -0.584255)
			(end 1.295492 0.584255)
			(stroke
				(width 0.1524)
				(type default)
			)
			(layer "F.SilkS")
		)
		(fp_line
			(start 1.295492 0.584255)
			(end -1.295492 0.584255)
			(stroke
				(width 0.1524)
				(type default)
			)
			(layer "F.SilkS")
		)
		(fp_line
			(start -1.295492 -0.584255)
			(end 1.295492 -0.584255)
			(stroke
				(width 0.1524)
				(type default)
			)
			(layer "F.SilkS")
		)
		(fp_line
			(start -1.295492 0.584255)
			(end -1.295492 -0.584255)
			(stroke
				(width 0.1524)
				(type default)
			)
			(layer "F.SilkS")
		)
		(fp_line
			(start 1.193656 -0.406626)
			(end 1.193835 0.406446)
			(stroke
				(width 0.1)
				(type default)
			)
			(layer "F.Fab")
		)
		(fp_line
			(start 0.863541 -0.457275)
			(end 0.863541 -0.406626)
			(stroke
				(width 0.1)
				(type default)
			)
			(layer "F.Fab")
		)
		(fp_line
			(start 0.863541 -0.406626)
			(end 1.193656 -0.406626)
			(stroke
				(width 0.1)
				(type default)
			)
			(layer "F.Fab")
		)
		(fp_line
			(start 1.193835 0.406446)
			(end 0.863721 0.406446)
			(stroke
				(width 0.1)
				(type default)
			)
			(layer "F.Fab")
		)
		(fp_line
			(start 0.863721 0.406446)
			(end 0.863541 0.457275)
			(stroke
				(width 0.1)
				(type default)
			)
			(layer "F.Fab")
		)
		(fp_line
			(start 0.863541 0.457275)
			(end -0.863541 0.457275)
			(stroke
				(width 0.1)
				(type default)
			)
			(layer "F.Fab")
		)
		(fp_line
			(start -0.863541 -0.457275)
			(end 0.863541 -0.457275)
			(stroke
				(width 0.1)
				(type default)
			)
			(layer "F.Fab")
		)
		(fp_line
			(start -0.863541 -0.406626)
			(end -0.863541 -0.457275)
			(stroke
				(width 0.1)
				(type default)
			)
			(layer "F.Fab")
		)
		(fp_line
			(start -1.193656 -0.406626)
			(end -0.863541 -0.406626)
			(stroke
				(width 0.1)
				(type default)
			)
			(layer "F.Fab")
		)
		(fp_line
			(start -0.863721 0.406446)
			(end -1.193835 0.406446)
			(stroke
				(width 0.1)
				(type default)
			)
			(layer "F.Fab")
		)
		(fp_line
			(start -0.863541 0.431771)
			(end -0.863721 0.406446)
			(stroke
				(width 0.1)
				(type default)
			)
			(layer "F.Fab")
		)
		(fp_line
			(start -0.863541 0.457275)
			(end -0.863541 0.431771)
			(stroke
				(width 0.1)
				(type default)
			)
			(layer "F.Fab")
		)
		(fp_line
			(start -1.193835 0.406446)
			(end -1.193656 -0.406626)
			(stroke
				(width 0.1)
				(type default)
			)
			(layer "F.Fab")
		)
		(pad "1" smd rect
			(at -0.7366 0 45)
			(size 0.7112 0.8128)
			(layers "F.Cu" "F.Mask" "F.Paste")
			(net "XTAL_PCH_RTC2_R")
		)
		(pad "2" smd rect
			(at 0.7366 0 45)
			(size 0.7112 0.8128)
			(layers "F.Cu" "F.Mask" "F.Paste")
			(net "XTAL_PCH_RTC1")
		)
	)
	(footprint ""
		(layer "F.Cu")
		(at 258.21386 -48.304704 180)
		(property "Reference" "R3943"
			(at 0 0 180)
			(layer "F.SilkS")
			(hide yes)
			(effects
				(font
					(size 1.27 1.27)
				)
			)
		)
		(property "Value" ""
			(at 0 0 180)
			(layer "F.Fab")
			(effects
				(font
					(size 1.27 1.27)
				)
			)
		)
		(duplicate_pad_numbers_are_jumpers no)
		(fp_line
			(start 0.7874 0.4064)
			(end -0.7874 0.4064)
			(stroke
				(width 0.1524)
				(type default)
			)
			(layer "F.SilkS")
		)
		(fp_line
			(start 0.7874 -0.4064)
			(end 0.7874 0.4064)
			(stroke
				(width 0.1524)
				(type default)
			)
			(layer "F.SilkS")
		)
		(fp_line
			(start -0.7874 0.4064)
			(end -0.7874 -0.4064)
			(stroke
				(width 0.1524)
				(type default)
			)
			(layer "F.SilkS")
		)
		(fp_line
			(start -0.7874 -0.4064)
			(end 0.7874 -0.4064)
			(stroke
				(width 0.1524)
				(type default)
			)
			(layer "F.SilkS")
		)
		(fp_line
			(start 0.67945 0.3048)
			(end 0.120396 0.3048)
			(stroke
				(width 0.1)
				(type default)
			)
			(layer "F.Fab")
		)
		(fp_line
			(start 0.67945 -0.3048)
			(end 0.67945 0.3048)
			(stroke
				(width 0.1)
				(type default)
			)
			(layer "F.Fab")
		)
		(fp_line
			(start 0.12065 -0.2794)
			(end 0.12065 -0.3048)
			(stroke
				(width 0.1)
				(type default)
			)
			(layer "F.Fab")
		)
		(fp_line
			(start 0.12065 -0.3048)
			(end 0.67945 -0.3048)
			(stroke
				(width 0.1)
				(type default)
			)
			(layer "F.Fab")
		)
		(fp_line
			(start 0.120396 0.3048)
			(end 0.120396 0.2794)
			(stroke
				(width 0.1)
				(type default)
			)
			(layer "F.Fab")
		)
		(fp_line
			(start 0.120396 0.2794)
			(end -0.12065 0.2794)
			(stroke
				(width 0.1)
				(type default)
			)
			(layer "F.Fab")
		)
		(fp_line
			(start -0.12065 0.3048)
			(end -0.67945 0.3048)
			(stroke
				(width 0.1)
				(type default)
			)
			(layer "F.Fab")
		)
		(fp_line
			(start -0.12065 0.2794)
			(end -0.12065 0.3048)
			(stroke
				(width 0.1)
				(type default)
			)
			(layer "F.Fab")
		)
		(fp_line
			(start -0.12065 -0.2794)
			(end 0.12065 -0.2794)
			(stroke
				(width 0.1)
				(type default)
			)
			(layer "F.Fab")
		)
		(fp_line
			(start -0.12065 -0.305054)
			(end -0.12065 -0.2794)
			(stroke
				(width 0.1)
				(type default)
			)
			(layer "F.Fab")
		)
		(fp_line
			(start -0.67945 0.3048)
			(end -0.67945 -0.305054)
			(stroke
				(width 0.1)
				(type default)
			)
			(layer "F.Fab")
		)
		(fp_line
			(start -0.67945 -0.305054)
			(end -0.12065 -0.305054)
			(stroke
				(width 0.1)
				(type default)
			)
			(layer "F.Fab")
		)
		(pad "1" smd circle
			(at -0.40005 0 180)
			(size 0 0)
			(layers "F.Cu" "F.Mask" "F.Paste")
			(net "E1S_0_EN")
		)
		(pad "2" smd circle
			(at 0.40005 0 180)
			(size 0 0)
			(layers "F.Cu" "F.Mask" "F.Paste")
			(net "P12V_E1S_EN_0_R2")
		)
	)
	(footprint ""
		(layer "F.Cu")
		(at 24.777446 -174.51451 90)
		(property "Reference" "PR4700"
			(at 0 0 90)
			(layer "F.SilkS")
			(hide yes)
			(effects
				(font
					(size 1.27 1.27)
				)
			)
		)
		(property "Value" ""
			(at 0 0 90)
			(layer "F.Fab")
			(effects
				(font
					(size 1.27 1.27)
				)
			)
		)
		(duplicate_pad_numbers_are_jumpers no)
		(fp_line
			(start 0.7874 -0.4064)
			(end 0.7874 0.4064)
			(stroke
				(width 0.1524)
				(type default)
			)
			(layer "F.SilkS")
		)
		(fp_line
			(start -0.7874 -0.4064)
			(end 0.7874 -0.4064)
			(stroke
				(width 0.1524)
				(type default)
			)
			(layer "F.SilkS")
		)
		(fp_line
			(start 0.7874 0.4064)
			(end -0.7874 0.4064)
			(stroke
				(width 0.1524)
				(type default)
			)
			(layer "F.SilkS")
		)
		(fp_line
			(start -0.7874 0.4064)
			(end -0.7874 -0.4064)
			(stroke
				(width 0.1524)
				(type default)
			)
			(layer "F.SilkS")
		)
		(fp_line
			(start -0.12065 -0.305054)
			(end -0.12065 -0.2794)
			(stroke
				(width 0.1)
				(type default)
			)
			(layer "F.Fab")
		)
		(fp_line
			(start -0.67945 -0.305054)
			(end -0.12065 -0.305054)
			(stroke
				(width 0.1)
				(type default)
			)
			(layer "F.Fab")
		)
		(fp_line
			(start 0.67945 -0.3048)
			(end 0.67945 0.3048)
			(stroke
				(width 0.1)
				(type default)
			)
			(layer "F.Fab")
		)
		(fp_line
			(start 0.12065 -0.3048)
			(end 0.67945 -0.3048)
			(stroke
				(width 0.1)
				(type default)
			)
			(layer "F.Fab")
		)
		(fp_line
			(start 0.12065 -0.2794)
			(end 0.12065 -0.3048)
			(stroke
				(width 0.1)
				(type default)
			)
			(layer "F.Fab")
		)
		(fp_line
			(start -0.12065 -0.2794)
			(end 0.12065 -0.2794)
			(stroke
				(width 0.1)
				(type default)
			)
			(layer "F.Fab")
		)
		(fp_line
			(start 0.120396 0.2794)
			(end -0.12065 0.2794)
			(stroke
				(width 0.1)
				(type default)
			)
			(layer "F.Fab")
		)
		(fp_line
			(start -0.12065 0.2794)
			(end -0.12065 0.3048)
			(stroke
				(width 0.1)
				(type default)
			)
			(layer "F.Fab")
		)
		(fp_line
			(start 0.67945 0.3048)
			(end 0.120396 0.3048)
			(stroke
				(width 0.1)
				(type default)
			)
			(layer "F.Fab")
		)
		(fp_line
			(start 0.120396 0.3048)
			(end 0.120396 0.2794)
			(stroke
				(width 0.1)
				(type default)
			)
			(layer "F.Fab")
		)
		(fp_line
			(start -0.12065 0.3048)
			(end -0.67945 0.3048)
			(stroke
				(width 0.1)
				(type default)
			)
			(layer "F.Fab")
		)
		(fp_line
			(start -0.67945 0.3048)
			(end -0.67945 -0.305054)
			(stroke
				(width 0.1)
				(type default)
			)
			(layer "F.Fab")
		)
		(pad "1" smd circle
			(at -0.40005 0 90)
			(size 0 0)
			(layers "F.Cu" "F.Mask" "F.Paste")
			(net "PVNN_MAIN_CPU1_FB_RC")
		)
		(pad "2" smd circle
			(at 0.40005 0 90)
			(size 0 0)
			(layers "F.Cu" "F.Mask" "F.Paste")
			(net "PVNN_MAIN_CPU1")
		)
	)
)
